(kicad_pcb
	(version 20260206)
	(generator "pcbnew")
	(generator_version "10.0")
	(general
		(thickness 1.6)
		(legacy_teardrops no)
	)
	(paper "A4")
	(title_block
		(title "Bryce Canyon_IOM_IOC_16318-2_OCP.brd")
		(comment 1 "Bryce Canyon / footprints 210-214 of 1605")
	)
	(layers
		(0 "F.Cu" signal "TOP")
		(4 "In1.Cu" signal "L2GND")
		(6 "In2.Cu" signal "L3")
		(8 "In3.Cu" signal "L4VCC")
		(10 "In4.Cu" signal "L5VCC")
		(12 "In5.Cu" signal "L6")
		(14 "In6.Cu" signal "L7GND")
		(2 "B.Cu" signal "BOTTOM")
		(9 "F.Adhes" user "F.Adhesive")
		(11 "B.Adhes" user "B.Adhesive")
		(13 "F.Paste" user "Package Geometry/Pastemask Top")
		(15 "B.Paste" user "Package Geometry/Pastemask Bottom")
		(5 "F.SilkS" user "Ref Des/Silkscreen Top")
		(7 "B.SilkS" user "Ref Des/Silkscreen Bottom")
		(1 "F.Mask" user "Board Geometry/Soldermask Top")
		(3 "B.Mask" user "Board Geometry/Soldermask Bottom")
		(17 "Dwgs.User" user "User.Drawings")
		(19 "Cmts.User" user "User.Comments")
		(21 "Eco1.User" user "User.Eco1")
		(23 "Eco2.User" user "User.Eco2")
		(25 "Edge.Cuts" user "Board Geometry/Outline")
		(27 "Margin" user)
		(31 "F.CrtYd" user "Package Geometry/Place Bound Top")
		(29 "B.CrtYd" user "Package Geometry/Place Bound Bottom")
		(35 "F.Fab" user "Ref Des/Assembly Top")
		(33 "B.Fab" user "Ref Des/Assembly Bottom")
	)
	(footprint ""
		(layer "F.Cu")
		(at 98.916744 -157.404054 -90)
		(property "Reference" "R18"
			(at 0 0 270)
			(layer "F.SilkS")
			(hide yes)
			(effects
				(font
					(size 1.27 1.27)
				)
			)
		)
		(property "Value" "4K7R2F-GP"
			(at 0.064008 -3.993896 270)
			(unlocked yes)
			(layer "F.Fab")
			(hide yes)
			(effects
				(font
					(size 1.016 1.016)
					(thickness 0.1524)
				)
			)
		)
		(property "Device Type" "R402H16"
			(at 0.064008 -5.517896 270)
			(unlocked yes)
			(layer "F.Fab")
			(hide yes)
			(effects
				(font
					(size 1.016 1.016)
					(thickness 0.1524)
				)
			)
		)
		(duplicate_pad_numbers_are_jumpers no)
		(fp_line
			(start -0.508 -0.9398)
			(end -0.508 0.9398)
			(stroke
				(width 0.1524)
				(type default)
			)
			(layer "F.SilkS")
		)
		(fp_line
			(start 0.508 -0.9398)
			(end -0.508 -0.9398)
			(stroke
				(width 0.1524)
				(type default)
			)
			(layer "F.SilkS")
		)
		(fp_rect
			(start -0.508 0.9398)
			(end 0.508 -0.9398)
			(stroke
				(width 0)
				(type default)
			)
			(fill no)
			(layer "F.CrtYd")
		)
		(fp_rect
			(start -0.508 0.9398)
			(end 0.508 -0.9398)
			(stroke
				(width 0)
				(type default)
			)
			(fill no)
			(layer "F.Fab")
		)
		(pad "1" smd custom
			(at 0 -0.4445 270)
			(size 0.1397 0.1397)
			(layers "F.Cu" "F.Mask" "F.Paste")
			(net "P3V3_STBY")
			(options
				(clearance outline)
				(anchor circle)
			)
			(primitives
				(gr_poly
					(pts
						(arc
							(start -0.1778 -0.2794)
							(mid -0.249642 -0.249642)
							(end -0.2794 -0.1778)
						)
						(arc
							(start -0.2794 0.1778)
							(mid -0.249642 0.249642)
							(end -0.1778 0.2794)
						)
						(arc
							(start 0.1778 0.2794)
							(mid 0.249642 0.249642)
							(end 0.2794 0.1778)
						)
						(arc
							(start 0.2794 -0.1778)
							(mid 0.249642 -0.249642)
							(end 0.1778 -0.2794)
						)
					)
					(width 0)
					(fill yes)
				)
			)
		)
		(pad "2" smd custom
			(at 0 0.4445 270)
			(size 0.1397 0.1397)
			(layers "F.Cu" "F.Mask" "F.Paste")
			(net "CFG_SEL1")
			(options
				(clearance outline)
				(anchor circle)
			)
			(primitives
				(gr_poly
					(pts
						(arc
							(start -0.1778 -0.2794)
							(mid -0.249642 -0.249642)
							(end -0.2794 -0.1778)
						)
						(arc
							(start -0.2794 0.1778)
							(mid -0.249642 0.249642)
							(end -0.1778 0.2794)
						)
						(arc
							(start 0.1778 0.2794)
							(mid 0.249642 0.249642)
							(end 0.2794 0.1778)
						)
						(arc
							(start 0.2794 -0.1778)
							(mid 0.249642 -0.249642)
							(end 0.1778 -0.2794)
						)
					)
					(width 0)
					(fill yes)
				)
			)
		)
	)
	(footprint ""
		(layer "F.Cu")
		(at 197.866 -131.699 90)
		(property "Reference" "R550"
			(at 0 0 90)
			(layer "F.SilkS")
			(hide yes)
			(effects
				(font
					(size 1.27 1.27)
				)
			)
		)
		(property "Value" "4K7R2F-GP"
			(at 0.064008 -3.993896 90)
			(unlocked yes)
			(layer "F.Fab")
			(hide yes)
			(effects
				(font
					(size 1.016 1.016)
					(thickness 0.1524)
				)
			)
		)
		(property "Device Type" "R402H16"
			(at 0.064008 -5.517896 90)
			(unlocked yes)
			(layer "F.Fab")
			(hide yes)
			(effects
				(font
					(size 1.016 1.016)
					(thickness 0.1524)
				)
			)
		)
		(duplicate_pad_numbers_are_jumpers no)
		(fp_line
			(start 0.508 -0.9398)
			(end -0.508 -0.9398)
			(stroke
				(width 0.1524)
				(type default)
			)
			(layer "F.SilkS")
		)
		(fp_line
			(start -0.508 -0.9398)
			(end -0.508 0.9398)
			(stroke
				(width 0.1524)
				(type default)
			)
			(layer "F.SilkS")
		)
		(fp_rect
			(start -0.508 0.9398)
			(end 0.508 -0.9398)
			(stroke
				(width 0)
				(type default)
			)
			(fill no)
			(layer "F.CrtYd")
		)
		(fp_rect
			(start -0.508 0.9398)
			(end 0.508 -0.9398)
			(stroke
				(width 0)
				(type default)
			)
			(fill no)
			(layer "F.Fab")
		)
		(pad "1" smd custom
			(at 0 -0.4445 90)
			(size 0.1397 0.1397)
			(layers "F.Cu" "F.Mask" "F.Paste")
			(net "P1V8")
			(options
				(clearance outline)
				(anchor circle)
			)
			(primitives
				(gr_poly
					(pts
						(arc
							(start -0.1778 -0.2794)
							(mid -0.249642 -0.249642)
							(end -0.2794 -0.1778)
						)
						(arc
							(start -0.2794 0.1778)
							(mid -0.249642 0.249642)
							(end -0.1778 0.2794)
						)
						(arc
							(start 0.1778 0.2794)
							(mid 0.249642 0.249642)
							(end 0.2794 0.1778)
						)
						(arc
							(start 0.2794 -0.1778)
							(mid 0.249642 -0.249642)
							(end 0.1778 -0.2794)
						)
					)
					(width 0)
					(fill yes)
				)
			)
		)
		(pad "2" smd custom
			(at 0 0.4445 90)
			(size 0.1397 0.1397)
			(layers "F.Cu" "F.Mask" "F.Paste")
			(net "PWRGD_P1V8")
			(options
				(clearance outline)
				(anchor circle)
			)
			(primitives
				(gr_poly
					(pts
						(arc
							(start -0.1778 -0.2794)
							(mid -0.249642 -0.249642)
							(end -0.2794 -0.1778)
						)
						(arc
							(start -0.2794 0.1778)
							(mid -0.249642 0.249642)
							(end -0.1778 0.2794)
						)
						(arc
							(start 0.1778 0.2794)
							(mid 0.249642 0.249642)
							(end 0.2794 0.1778)
						)
						(arc
							(start 0.2794 -0.1778)
							(mid 0.249642 -0.249642)
							(end 0.1778 -0.2794)
						)
					)
					(width 0)
					(fill yes)
				)
			)
		)
	)
	(footprint ""
		(layer "F.Cu")
		(at 89.65692 -162.334956 180)
		(property "Reference" "C19"
			(at 0 0 180)
			(layer "F.SilkS")
			(hide yes)
			(effects
				(font
					(size 1.27 1.27)
				)
			)
		)
		(property "Value" "SC1U16V3KX-5GP"
			(at 0 -2.8194 180)
			(unlocked yes)
			(layer "F.Fab")
			(hide yes)
			(effects
				(font
					(size 1.016 1.016)
					(thickness 0.1524)
				)
			)
		)
		(property "Device Type" "C603H36"
			(at 0 -4.3434 180)
			(unlocked yes)
			(layer "F.Fab")
			(hide yes)
			(effects
				(font
					(size 1.016 1.016)
					(thickness 0.1524)
				)
			)
		)
		(duplicate_pad_numbers_are_jumpers no)
		(fp_line
			(start 0.508 0)
			(end -0.508 0)
			(stroke
				(width 0.2032)
				(type default)
			)
			(layer "F.SilkS")
		)
		(fp_rect
			(start -0.5842 1.3335)
			(end 0.5842 -1.3335)
			(stroke
				(width 0)
				(type default)
			)
			(fill no)
			(layer "F.CrtYd")
		)
		(fp_rect
			(start -0.5842 1.3335)
			(end 0.5842 -1.3335)
			(stroke
				(width 0)
				(type default)
			)
			(fill no)
			(layer "F.Fab")
		)
		(pad "1" smd custom
			(at 0 -0.762 180)
			(size 0.2159 0.2159)
			(layers "F.Cu" "F.Mask" "F.Paste")
			(net "PLLFILT")
			(options
				(clearance outline)
				(anchor circle)
			)
			(primitives
				(gr_poly
					(pts
						(arc
							(start -0.3302 -0.4318)
							(mid -0.402042 -0.402042)
							(end -0.4318 -0.3302)
						)
						(arc
							(start -0.4318 0.3302)
							(mid -0.402042 0.402042)
							(end -0.3302 0.4318)
						)
						(arc
							(start 0.3302 0.4318)
							(mid 0.402042 0.402042)
							(end 0.4318 0.3302)
						)
						(arc
							(start 0.4318 -0.3302)
							(mid 0.402042 -0.402042)
							(end 0.3302 -0.4318)
						)
					)
					(width 0)
					(fill yes)
				)
			)
		)
		(pad "2" smd custom
			(at 0 0.762 180)
			(size 0.2159 0.2159)
			(layers "F.Cu" "F.Mask" "F.Paste")
			(net "GND")
			(options
				(clearance outline)
				(anchor circle)
			)
			(primitives
				(gr_poly
					(pts
						(arc
							(start -0.3302 -0.4318)
							(mid -0.402042 -0.402042)
							(end -0.4318 -0.3302)
						)
						(arc
							(start -0.4318 0.3302)
							(mid -0.402042 0.402042)
							(end -0.3302 0.4318)
						)
						(arc
							(start 0.3302 0.4318)
							(mid 0.402042 0.402042)
							(end 0.4318 0.3302)
						)
						(arc
							(start 0.4318 -0.3302)
							(mid 0.402042 -0.402042)
							(end 0.3302 -0.4318)
						)
					)
					(width 0)
					(fill yes)
				)
			)
		)
	)
	(footprint ""
		(layer "F.Cu")
		(at 11.999976 -6.249924)
		(property "Reference" "RST1"
			(at 0 0 0)
			(layer "F.SilkS")
			(hide yes)
			(effects
				(font
					(size 1.27 1.27)
				)
			)
		)
		(property "Value" "SW-TACT-4P-210-GP"
			(at -5.9436 2.1209 0)
			(unlocked yes)
			(layer "F.Fab")
			(hide yes)
			(effects
				(font
					(size 1.016 1.016)
					(thickness 0.1524)
				)
			)
		)
		(property "Device Type" "DIPTRONICS"
			(at -5.9436 0.5969 0)
			(unlocked yes)
			(layer "F.Fab")
			(hide yes)
			(effects
				(font
					(size 1.016 1.016)
					(thickness 0.1524)
				)
			)
		)
		(duplicate_pad_numbers_are_jumpers no)
		(fp_line
			(start -4.4704 -4.2418)
			(end 4.4704 -4.2418)
			(stroke
				(width 0.1524)
				(type default)
			)
			(layer "F.SilkS")
		)
		(fp_line
			(start -4.4704 -1.5494)
			(end -4.4704 -4.2418)
			(stroke
				(width 0.1524)
				(type default)
			)
			(layer "F.SilkS")
		)
		(fp_line
			(start -3.9497 -1.5494)
			(end -4.4704 -1.5494)
			(stroke
				(width 0.1524)
				(type default)
			)
			(layer "F.SilkS")
		)
		(fp_line
			(start -3.9497 3.2258)
			(end -3.9497 -1.5494)
			(stroke
				(width 0.1524)
				(type default)
			)
			(layer "F.SilkS")
		)
		(fp_line
			(start -2.0066 3.2258)
			(end -3.9497 3.2258)
			(stroke
				(width 0.1524)
				(type default)
			)
			(layer "F.SilkS")
		)
		(fp_line
			(start -2.0066 6.1214)
			(end -2.0066 3.2258)
			(stroke
				(width 0.1524)
				(type default)
			)
			(layer "F.SilkS")
		)
		(fp_line
			(start 2.0066 3.2258)
			(end 2.0066 6.1214)
			(stroke
				(width 0.1524)
				(type default)
			)
			(layer "F.SilkS")
		)
		(fp_line
			(start 2.0066 6.1214)
			(end -2.0066 6.1214)
			(stroke
				(width 0.1524)
				(type default)
			)
			(layer "F.SilkS")
		)
		(fp_line
			(start 3.9497 -1.5494)
			(end 3.9497 3.2258)
			(stroke
				(width 0.1524)
				(type default)
			)
			(layer "F.SilkS")
		)
		(fp_line
			(start 3.9497 3.2258)
			(end 2.0066 3.2258)
			(stroke
				(width 0.1524)
				(type default)
			)
			(layer "F.SilkS")
		)
		(fp_line
			(start 4.4704 -4.2418)
			(end 4.4704 -1.5494)
			(stroke
				(width 0.1524)
				(type default)
			)
			(layer "F.SilkS")
		)
		(fp_line
			(start 4.4704 -1.5494)
			(end 3.9497 -1.5494)
			(stroke
				(width 0.1524)
				(type default)
			)
			(layer "F.SilkS")
		)
		(fp_circle
			(center -3.50012 -2.500122)
			(end -2.43332 -2.500122)
			(stroke
				(width 0.3048)
				(type default)
			)
			(fill no)
			(layer "F.SilkS")
		)
		(fp_circle
			(center -2.249932 0)
			(end -1.183132 0)
			(stroke
				(width 0.3048)
				(type default)
			)
			(fill no)
			(layer "F.SilkS")
		)
		(fp_circle
			(center 2.249932 0)
			(end 3.316732 0)
			(stroke
				(width 0.3048)
				(type default)
			)
			(fill no)
			(layer "F.SilkS")
		)
		(fp_circle
			(center 3.50012 -2.500122)
			(end 4.56692 -2.500122)
			(stroke
				(width 0.3048)
				(type default)
			)
			(fill no)
			(layer "F.SilkS")
		)
		(fp_poly
			(pts
				(xy -1.7526 5.8674) (xy -1.7526 2.9718) (xy -3.6957 2.9718) (xy -3.6957 -3.9878) (xy 3.6957 -3.9878)
				(xy 3.6957 2.9718) (xy 1.7526 2.9718) (xy 1.7526 5.8674)
			)
			(stroke
				(width 0)
				(type default)
			)
			(fill no)
			(layer "F.CrtYd")
		)
		(fp_poly
			(pts
				(xy -2.2606 6.3754) (xy -2.2606 3.4798) (xy -4.2037 3.4798) (xy -4.2037 -1.2954) (xy -4.7244 -1.2954)
				(xy -4.7244 -4.4958) (xy 4.7244 -4.4958) (xy 4.7244 -1.2954) (xy 4.2037 -1.2954) (xy 4.2037 -0.00635)
				(xy 3.6957 -0.00635) (xy 3.6957 -3.9878) (xy -3.6957 -3.9878) (xy -3.6957 2.9718) (xy -1.7526 2.9718)
				(xy -1.7526 5.8674) (xy 1.7526 5.8674) (xy 1.7526 2.9718) (xy 3.6957 2.9718) (xy 3.6957 0.00635)
				(xy 4.2037 0.00635) (xy 4.2037 3.4798) (xy 2.2606 3.4798) (xy 2.2606 6.3754)
			)
			(stroke
				(width 0)
				(type default)
			)
			(fill no)
			(layer "F.CrtYd")
		)
		(fp_poly
			(pts
				(xy -2.2606 6.3754) (xy -2.2606 3.4798) (xy -4.2037 3.4798) (xy -4.2037 -1.2954) (xy -4.7244 -1.2954)
				(xy -4.7244 -4.4958) (xy 4.7244 -4.4958) (xy 4.7244 -1.2954) (xy 4.2037 -1.2954) (xy 4.2037 3.4798)
				(xy 2.2606 3.4798) (xy 2.2606 6.3754)
			)
			(stroke
				(width 0)
				(type default)
			)
			(fill no)
			(layer "F.Fab")
		)
		(pad "1" thru_hole circle
			(at -2.249932 0)
			(size 1.4224 1.4224)
			(drill 1.016)
			(layers "*.Cu" "*.Mask")
			(remove_unused_layers no)
			(net "SYS_RST_BTN_IN_N")
			(clearance 0.1524)
			(thermal_gap 0.1524)
		)
		(pad "2" thru_hole circle
			(at 2.249932 0)
			(size 1.4224 1.4224)
			(drill 1.016)
			(layers "*.Cu" "*.Mask")
			(remove_unused_layers no)
			(net "GND")
			(clearance 0.1524)
			(thermal_gap 0.1524)
		)
		(pad "3" thru_hole circle
			(at -3.50012 -2.500122)
			(size 1.4224 1.4224)
			(drill 1.016)
			(layers "*.Cu" "*.Mask")
			(remove_unused_layers no)
			(net "RST_BTN_GND")
			(clearance 0.1524)
			(thermal_gap 0.1524)
		)
		(pad "4" thru_hole circle
			(at 3.50012 -2.500122)
			(size 1.4224 1.4224)
			(drill 1.016)
			(layers "*.Cu" "*.Mask")
			(remove_unused_layers no)
			(net "RST_BTN_GND")
			(clearance 0.1524)
			(thermal_gap 0.1524)
		)
		(zone
			(layer "F.Cu")
			(hatch none 0.5)
			(connect_pads
				(clearance 0)
			)
			(min_thickness 0.25)
			(keepout
				(tracks not_allowed)
				(vias allowed)
				(pads allowed)
				(copperpour not_allowed)
				(footprints allowed)
			)
			(placement
				(enabled no)
				(sheetname "")
			)
			(fill
				(thermal_gap 0.5)
				(thermal_bridge_width 0.5)
				(island_removal_mode 0)
			)
			(polygon
				(pts
					(xy 8.177276 -9.461246) (xy 8.837676 -9.461246) (xy 8.837676 -10.364724) (xy 8.177276 -10.364724)
				)
			)
		)
		(zone
			(layer "F.Cu")
			(hatch none 0.5)
			(connect_pads
				(clearance 0)
			)
			(min_thickness 0.25)
			(keepout
				(tracks allowed)
				(vias not_allowed)
				(pads allowed)
				(copperpour not_allowed)
				(footprints allowed)
			)
			(placement
				(enabled no)
				(sheetname "")
			)
			(fill
				(thermal_gap 0.5)
				(thermal_bridge_width 0.5)
				(island_removal_mode 0)
			)
			(polygon
				(pts
					(xy 8.177276 -9.461246) (xy 8.837676 -9.461246) (xy 8.837676 -10.364724) (xy 8.177276 -10.364724)
				)
			)
		)
		(zone
			(layer "F.Cu")
			(hatch none 0.5)
			(connect_pads
				(clearance 0)
			)
			(min_thickness 0.25)
			(keepout
				(tracks allowed)
				(vias not_allowed)
				(pads allowed)
				(copperpour not_allowed)
				(footprints allowed)
			)
			(placement
				(enabled no)
				(sheetname "")
			)
			(fill
				(thermal_gap 0.5)
				(thermal_bridge_width 0.5)
				(island_removal_mode 0)
			)
			(polygon
				(pts
					(xy 8.177276 -3.532124) (xy 8.837676 -3.532124) (xy 8.837676 -8.038846) (xy 8.177276 -8.038846)
				)
			)
		)
		(zone
			(layer "F.Cu")
			(hatch none 0.5)
			(connect_pads
				(clearance 0)
			)
			(min_thickness 0.25)
			(keepout
				(tracks not_allowed)
				(vias allowed)
				(pads allowed)
				(copperpour not_allowed)
				(footprints allowed)
			)
			(placement
				(enabled no)
				(sheetname "")
			)
			(fill
				(thermal_gap 0.5)
				(thermal_bridge_width 0.5)
				(island_removal_mode 0)
			)
			(polygon
				(pts
					(xy 8.177276 -3.532124) (xy 8.837676 -3.532124) (xy 8.837676 -8.038846) (xy 8.177276 -8.038846)
				)
			)
		)
		(zone
			(layer "F.Cu")
			(hatch none 0.5)
			(connect_pads
				(clearance 0)
			)
			(min_thickness 0.25)
			(keepout
				(tracks allowed)
				(vias not_allowed)
				(pads allowed)
				(copperpour not_allowed)
				(footprints allowed)
			)
			(placement
				(enabled no)
				(sheetname "")
			)
			(fill
				(thermal_gap 0.5)
				(thermal_bridge_width 0.5)
				(island_removal_mode 0)
			)
			(polygon
				(pts
					(xy 11.072876 -3.532124) (xy 12.927076 -3.532124) (xy 12.927076 -4.294124) (xy 11.072876 -4.294124)
				)
			)
		)
		(zone
			(layer "F.Cu")
			(hatch none 0.5)
			(connect_pads
				(clearance 0)
			)
			(min_thickness 0.25)
			(keepout
				(tracks not_allowed)
				(vias allowed)
				(pads allowed)
				(copperpour not_allowed)
				(footprints allowed)
			)
			(placement
				(enabled no)
				(sheetname "")
			)
			(fill
				(thermal_gap 0.5)
				(thermal_bridge_width 0.5)
				(island_removal_mode 0)
			)
			(polygon
				(pts
					(xy 11.072876 -3.532124) (xy 12.927076 -3.532124) (xy 12.927076 -4.294124) (xy 11.072876 -4.294124)
				)
			)
		)
		(zone
			(layer "F.Cu")
			(hatch none 0.5)
			(connect_pads
				(clearance 0)
			)
			(min_thickness 0.25)
			(keepout
				(tracks allowed)
				(vias not_allowed)
				(pads allowed)
				(copperpour not_allowed)
				(footprints allowed)
			)
			(placement
				(enabled no)
				(sheetname "")
			)
			(fill
				(thermal_gap 0.5)
				(thermal_bridge_width 0.5)
				(island_removal_mode 0)
			)
			(polygon
				(pts
					(xy 15.162276 -9.461246) (xy 15.822676 -9.461246) (xy 15.822676 -10.364724) (xy 15.162276 -10.364724)
				)
			)
		)
		(zone
			(layer "F.Cu")
			(hatch none 0.5)
			(connect_pads
				(clearance 0)
			)
			(min_thickness 0.25)
			(keepout
				(tracks not_allowed)
				(vias allowed)
				(pads allowed)
				(copperpour not_allowed)
				(footprints allowed)
			)
			(placement
				(enabled no)
				(sheetname "")
			)
			(fill
				(thermal_gap 0.5)
				(thermal_bridge_width 0.5)
				(island_removal_mode 0)
			)
			(polygon
				(pts
					(xy 15.162276 -9.461246) (xy 15.822676 -9.461246) (xy 15.822676 -10.364724) (xy 15.162276 -10.364724)
				)
			)
		)
		(zone
			(layer "F.Cu")
			(hatch none 0.5)
			(connect_pads
				(clearance 0)
			)
			(min_thickness 0.25)
			(keepout
				(tracks not_allowed)
				(vias allowed)
				(pads allowed)
				(copperpour not_allowed)
				(footprints allowed)
			)
			(placement
				(enabled no)
				(sheetname "")
			)
			(fill
				(thermal_gap 0.5)
				(thermal_bridge_width 0.5)
				(island_removal_mode 0)
			)
			(polygon
				(pts
					(xy 15.162276 -3.532124) (xy 15.822676 -3.532124) (xy 15.822676 -8.038846) (xy 15.162276 -8.038846)
				)
			)
		)
		(zone
			(layer "F.Cu")
			(hatch none 0.5)
			(connect_pads
				(clearance 0)
			)
			(min_thickness 0.25)
			(keepout
				(tracks allowed)
				(vias not_allowed)
				(pads allowed)
				(copperpour not_allowed)
				(footprints allowed)
			)
			(placement
				(enabled no)
				(sheetname "")
			)
			(fill
				(thermal_gap 0.5)
				(thermal_bridge_width 0.5)
				(island_removal_mode 0)
			)
			(polygon
				(pts
					(xy 15.162276 -3.532124) (xy 15.822676 -3.532124) (xy 15.822676 -8.038846) (xy 15.162276 -8.038846)
				)
			)
		)
	)
	(footprint ""
		(layer "F.Cu")
		(at 175.1076 -39.497)
		(property "Reference" "TP174"
			(at 0 0 0)
			(layer "F.SilkS")
			(hide yes)
			(effects
				(font
					(size 1.27 1.27)
				)
			)
		)
		(property "Value" "TPAD28-2-GP"
			(at -0.0127 -1.6637 0)
			(unlocked yes)
			(layer "F.Fab")
			(hide yes)
			(effects
				(font
					(size 1.016 1.016)
					(thickness 0.1524)
				)
			)
		)
		(property "Device Type" "TPAD28"
			(at -0.0127 -3.1877 0)
			(unlocked yes)
			(layer "F.Fab")
			(hide yes)
			(effects
				(font
					(size 1.016 1.016)
					(thickness 0.1524)
				)
			)
		)
		(duplicate_pad_numbers_are_jumpers no)
		(fp_poly
			(pts
				(arc
					(start 0.3556 0)
					(mid -0.3556 0)
					(end 0.3556 0)
				)
			)
			(stroke
				(width 0)
				(type default)
			)
			(fill no)
			(layer "F.CrtYd")
		)
		(fp_poly
			(pts
				(arc
					(start 0.6096 0)
					(mid -0.6096 0)
					(end 0.6096 0)
				)
			)
			(stroke
				(width 0)
				(type default)
			)
			(fill no)
			(layer "F.Fab")
		)
		(pad "1" smd circle
			(at 0 0)
			(size 0.7112 0.7112)
			(layers "F.Cu" "F.Mask" "F.Paste")
			(net "ZDEF_EXTA_TP_B1")
		)
	)
)
